# S9S_MB_2U (Grand Teton) — schematic netlist excerpt (pin names and nets, part order shuffled) for the footprints in the layout excerpt that follows; sources: Cadence DE-HDL packaged netlist, KiCad conversion of 03242023_DA0F0TMBIJ0_F0T_Motherboard_J_brd_V01_OCP.brd

C730  Q_CAP_DIFFBUS  DIFF BUS_0.22UF 6.3V 20% X6S  pkg C0201  page 176 : \1\ = P5E_CPU1_PE0_TX_C_DN<5> ; \2\ = P5E_CPU1_PE0_TX_DN<5>
PC2277  Q_CAP  0.01UF 25V 10% X7R  pkg 0402  page 300 : A = PVNN_MAIN_CPU1_FB_RC ; B = GND
PR502  Q_RES  8.25K 0.1% CHIP  pkg 0402LF  page 300 : A = PVNN_MAIN_CPU1_FB ; B = PVNN_MAIN_CPU1_FB_RC

(kicad_pcb
	(version 20260206)
	(generator "pcbnew")
	(generator_version "10.0")
	(general
		(thickness 1.6)
		(legacy_teardrops no)
	)
	(paper "A4")
	(title_block
		(title "03242023_DA0F0TMBIJ0_F0T_Motherboard_J_brd_V01_OCP.brd")
		(comment 1 "Grand Teton / footprints 2364-2366 of 6105")
	)
	(layers
		(0 "F.Cu" signal "TOP")
		(4 "In1.Cu" signal "GND")
		(6 "In2.Cu" signal "IN1")
		(8 "In3.Cu" signal "GND1")
		(10 "In4.Cu" signal "IN2")
		(12 "In5.Cu" signal "GND2")
		(14 "In6.Cu" signal "IN3")
		(16 "In7.Cu" signal "GND3")
		(18 "In8.Cu" signal "VCC")
		(20 "In9.Cu" signal "VCC1")
		(22 "In10.Cu" signal "GND4")
		(24 "In11.Cu" signal "IN4")
		(26 "In12.Cu" signal "GND5")
		(28 "In13.Cu" signal "IN5")
		(30 "In14.Cu" signal "GND6")
		(32 "In15.Cu" signal "IN6")
		(34 "In16.Cu" signal "GND7")
		(2 "B.Cu" signal "BOTTOM")
		(9 "F.Adhes" user "F.Adhesive")
		(11 "B.Adhes" user "B.Adhesive")
		(13 "F.Paste" user "Package Geometry/Pastemask Top")
		(15 "B.Paste" user "Package Geometry/Pastemask Bottom")
		(5 "F.SilkS" user "Ref Des/Silkscreen Top")
		(7 "B.SilkS" user "Ref Des/Silkscreen Bottom")
		(1 "F.Mask" user "Board Geometry/Soldermask Top")
		(3 "B.Mask" user "Board Geometry/Soldermask Bottom")
		(17 "Dwgs.User" user "User.Drawings")
		(19 "Cmts.User" user "User.Comments")
		(21 "Eco1.User" user "User.Eco1")
		(23 "Eco2.User" user "User.Eco2")
		(25 "Edge.Cuts" user "Board Geometry/Outline")
		(27 "Margin" user)
		(31 "F.CrtYd" user "Package Geometry/Place Bound Top")
		(29 "B.CrtYd" user "Package Geometry/Place Bound Bottom")
		(35 "F.Fab" user "Ref Des/Assembly Top")
		(33 "B.Fab" user "Ref Des/Assembly Bottom")
	)
	(footprint ""
		(layer "F.Cu")
		(at 78.586838 -402.371052 -90)
		(property "Reference" "C730"
			(at 0 0 270)
			(layer "F.SilkS")
			(hide yes)
			(effects
				(font
					(size 1.27 1.27)
				)
			)
		)
		(property "Value" ""
			(at 0 0 270)
			(layer "F.Fab")
			(effects
				(font
					(size 1.27 1.27)
				)
			)
		)
		(duplicate_pad_numbers_are_jumpers no)
		(fp_line
			(start -0.299974 0.150114)
			(end -0.299974 -0.150114)
			(stroke
				(width 0.1)
				(type default)
			)
			(layer "F.Fab")
		)
		(fp_line
			(start 0.299974 0.150114)
			(end -0.299974 0.150114)
			(stroke
				(width 0.1)
				(type default)
			)
			(layer "F.Fab")
		)
		(fp_line
			(start -0.299974 -0.150114)
			(end 0.299974 -0.150114)
			(stroke
				(width 0.1)
				(type default)
			)
			(layer "F.Fab")
		)
		(fp_line
			(start 0.299974 -0.150114)
			(end 0.299974 0.150114)
			(stroke
				(width 0.1)
				(type default)
			)
			(layer "F.Fab")
		)
		(pad "1" smd rect
			(at -0.2667 0 270)
			(size 0.3048 0.381)
			(layers "F.Cu" "F.Mask" "F.Paste")
			(net "P5E_CPU1_PE0_TX_C_DN<5>")
		)
		(pad "2" smd rect
			(at 0.2667 0 270)
			(size 0.3048 0.381)
			(layers "F.Cu" "F.Mask" "F.Paste")
			(net "P5E_CPU1_PE0_TX_DN<5>")
		)
	)
	(footprint ""
		(layer "F.Cu")
		(at 22.354032 -175.423576)
		(property "Reference" "PR502"
			(at 0 0 0)
			(layer "F.SilkS")
			(hide yes)
			(effects
				(font
					(size 1.27 1.27)
				)
			)
		)
		(property "Value" ""
			(at 0 0 0)
			(layer "F.Fab")
			(effects
				(font
					(size 1.27 1.27)
				)
			)
		)
		(duplicate_pad_numbers_are_jumpers no)
		(fp_line
			(start -0.7874 -0.4064)
			(end 0.7874 -0.4064)
			(stroke
				(width 0.1524)
				(type default)
			)
			(layer "F.SilkS")
		)
		(fp_line
			(start -0.7874 0.4064)
			(end -0.7874 -0.4064)
			(stroke
				(width 0.1524)
				(type default)
			)
			(layer "F.SilkS")
		)
		(fp_line
			(start 0.7874 -0.4064)
			(end 0.7874 0.4064)
			(stroke
				(width 0.1524)
				(type default)
			)
			(layer "F.SilkS")
		)
		(fp_line
			(start 0.7874 0.4064)
			(end -0.7874 0.4064)
			(stroke
				(width 0.1524)
				(type default)
			)
			(layer "F.SilkS")
		)
		(fp_line
			(start -0.67945 -0.305054)
			(end -0.12065 -0.305054)
			(stroke
				(width 0.1)
				(type default)
			)
			(layer "F.Fab")
		)
		(fp_line
			(start -0.67945 0.3048)
			(end -0.67945 -0.305054)
			(stroke
				(width 0.1)
				(type default)
			)
			(layer "F.Fab")
		)
		(fp_line
			(start -0.12065 -0.305054)
			(end -0.12065 -0.2794)
			(stroke
				(width 0.1)
				(type default)
			)
			(layer "F.Fab")
		)
		(fp_line
			(start -0.12065 -0.2794)
			(end 0.12065 -0.2794)
			(stroke
				(width 0.1)
				(type default)
			)
			(layer "F.Fab")
		)
		(fp_line
			(start -0.12065 0.2794)
			(end -0.12065 0.3048)
			(stroke
				(width 0.1)
				(type default)
			)
			(layer "F.Fab")
		)
		(fp_line
			(start -0.12065 0.3048)
			(end -0.67945 0.3048)
			(stroke
				(width 0.1)
				(type default)
			)
			(layer "F.Fab")
		)
		(fp_line
			(start 0.120396 0.2794)
			(end -0.12065 0.2794)
			(stroke
				(width 0.1)
				(type default)
			)
			(layer "F.Fab")
		)
		(fp_line
			(start 0.120396 0.3048)
			(end 0.120396 0.2794)
			(stroke
				(width 0.1)
				(type default)
			)
			(layer "F.Fab")
		)
		(fp_line
			(start 0.12065 -0.3048)
			(end 0.67945 -0.3048)
			(stroke
				(width 0.1)
				(type default)
			)
			(layer "F.Fab")
		)
		(fp_line
			(start 0.12065 -0.2794)
			(end 0.12065 -0.3048)
			(stroke
				(width 0.1)
				(type default)
			)
			(layer "F.Fab")
		)
		(fp_line
			(start 0.67945 -0.3048)
			(end 0.67945 0.3048)
			(stroke
				(width 0.1)
				(type default)
			)
			(layer "F.Fab")
		)
		(fp_line
			(start 0.67945 0.3048)
			(end 0.120396 0.3048)
			(stroke
				(width 0.1)
				(type default)
			)
			(layer "F.Fab")
		)
		(pad "1" smd circle
			(at -0.40005 0)
			(size 0 0)
			(layers "F.Cu" "F.Mask" "F.Paste")
			(net "PVNN_MAIN_CPU1_FB")
		)
		(pad "2" smd circle
			(at 0.40005 0)
			(size 0 0)
			(layers "F.Cu" "F.Mask" "F.Paste")
			(net "PVNN_MAIN_CPU1_FB_RC")
		)
	)
	(footprint ""
		(layer "F.Cu")
		(at 23.760938 -174.53483 90)
		(property "Reference" "PC2277"
			(at 0 0 90)
			(layer "F.SilkS")
			(hide yes)
			(effects
				(font
					(size 1.27 1.27)
				)
			)
		)
		(property "Value" ""
			(at 0 0 90)
			(layer "F.Fab")
			(effects
				(font
					(size 1.27 1.27)
				)
			)
		)
		(duplicate_pad_numbers_are_jumpers no)
		(fp_line
			(start 0.7874 -0.4064)
			(end 0.7874 0.4064)
			(stroke
				(width 0.1524)
				(type default)
			)
			(layer "F.SilkS")
		)
		(fp_line
			(start -0.7874 -0.4064)
			(end 0.7874 -0.4064)
			(stroke
				(width 0.1524)
				(type default)
			)
			(layer "F.SilkS")
		)
		(fp_line
			(start 0.7874 0.4064)
			(end -0.7874 0.4064)
			(stroke
				(width 0.1524)
				(type default)
			)
			(layer "F.SilkS")
		)
		(fp_line
			(start -0.7874 0.4064)
			(end -0.7874 -0.4064)
			(stroke
				(width 0.1524)
				(type default)
			)
			(layer "F.SilkS")
		)
		(fp_line
			(start -0.12065 -0.305054)
			(end -0.12065 -0.2794)
			(stroke
				(width 0.1)
				(type default)
			)
			(layer "F.Fab")
		)
		(fp_line
			(start -0.67945 -0.305054)
			(end -0.12065 -0.305054)
			(stroke
				(width 0.1)
				(type default)
			)
			(layer "F.Fab")
		)
		(fp_line
			(start 0.67945 -0.3048)
			(end 0.67945 0.3048)
			(stroke
				(width 0.1)
				(type default)
			)
			(layer "F.Fab")
		)
		(fp_line
			(start 0.12065 -0.3048)
			(end 0.67945 -0.3048)
			(stroke
				(width 0.1)
				(type default)
			)
			(layer "F.Fab")
		)
		(fp_line
			(start 0.12065 -0.2794)
			(end 0.12065 -0.3048)
			(stroke
				(width 0.1)
				(type default)
			)
			(layer "F.Fab")
		)
		(fp_line
			(start -0.12065 -0.2794)
			(end 0.12065 -0.2794)
			(stroke
				(width 0.1)
				(type default)
			)
			(layer "F.Fab")
		)
		(fp_line
			(start 0.120396 0.2794)
			(end -0.12065 0.2794)
			(stroke
				(width 0.1)
				(type default)
			)
			(layer "F.Fab")
		)
		(fp_line
			(start -0.12065 0.2794)
			(end -0.12065 0.3048)
			(stroke
				(width 0.1)
				(type default)
			)
			(layer "F.Fab")
		)
		(fp_line
			(start 0.67945 0.3048)
			(end 0.120396 0.3048)
			(stroke
				(width 0.1)
				(type default)
			)
			(layer "F.Fab")
		)
		(fp_line
			(start 0.120396 0.3048)
			(end 0.120396 0.2794)
			(stroke
				(width 0.1)
				(type default)
			)
			(layer "F.Fab")
		)
		(fp_line
			(start -0.12065 0.3048)
			(end -0.67945 0.3048)
			(stroke
				(width 0.1)
				(type default)
			)
			(layer "F.Fab")
		)
		(fp_line
			(start -0.67945 0.3048)
			(end -0.67945 -0.305054)
			(stroke
				(width 0.1)
				(type default)
			)
			(layer "F.Fab")
		)
		(pad "1" smd circle
			(at -0.40005 0 90)
			(size 0 0)
			(layers "F.Cu" "F.Mask" "F.Paste")
			(net "PVNN_MAIN_CPU1_FB_RC")
		)
		(pad "2" smd circle
			(at 0.40005 0 90)
			(size 0 0)
			(layers "F.Cu" "F.Mask" "F.Paste")
			(net "GND")
		)
	)
)
